(kicad_pcb
	(version 20241229)
	(generator "pcbnew")
	(generator_version "9.0")
	(general
		(thickness 1.61)
		(legacy_teardrops no)
	)
	(paper "A3")
	(title_block
		(title "RDIMM DDR5 Tester")
		(date "2026-05-21")
		(rev "2.2.0")
		(company "Antmicro")
		(comment 9 "footprints 558-561 of 796")
	)
	(layers
		(0 "F.Cu" signal)
		(4 "In1.Cu" power)
		(6 "In2.Cu" mixed)
		(8 "In3.Cu" power)
		(10 "In4.Cu" mixed)
		(12 "In5.Cu" power)
		(14 "In6.Cu" mixed)
		(16 "In7.Cu" power)
		(18 "In8.Cu" power)
		(20 "In9.Cu" mixed)
		(22 "In10.Cu" power)
		(2 "B.Cu" signal)
		(9 "F.Adhes" user "F.Adhesive")
		(11 "B.Adhes" user "B.Adhesive")
		(13 "F.Paste" user)
		(15 "B.Paste" user)
		(5 "F.SilkS" user "F.Silkscreen")
		(7 "B.SilkS" user "B.Silkscreen")
		(1 "F.Mask" user)
		(3 "B.Mask" user)
		(17 "Dwgs.User" user "User.Drawings")
		(19 "Cmts.User" user "User.Comments")
		(21 "Eco1.User" user "User.Eco1")
		(23 "Eco2.User" user "User.Eco2")
		(25 "Edge.Cuts" user)
		(27 "Margin" user)
		(31 "F.CrtYd" user "F.Courtyard")
		(29 "B.CrtYd" user "B.Courtyard")
		(35 "F.Fab" user)
		(33 "B.Fab" user)
	)
	(footprint "antmicro-footprints:USON-10_2.5x1mm_P0.5mm"
		(layer "B.Cu")
		(at 107.804 163.868 180)
		(descr "USON-10 2.5x1mm_ Pitch 0.5mm")
		(tags "USON-10 2.5x1mm Pitch 0.5mm")
		(property "Reference" "U47"
			(at -2.174 -0.782 90)
			(layer "B.SilkS")
			(effects
				(font
					(size 0.7 0.7)
					(thickness 0.15)
				)
				(justify right bottom mirror)
			)
		)
		(property "Value" "TPD4E05U06QDQARQ1"
			(at 0.018 -2.499 0)
			(layer "B.Fab")
			(effects
				(font
					(size 0.7 0.7)
					(thickness 0.15)
				)
				(justify left bottom mirror)
			)
		)
		(property "Datasheet" "https://www.ti.com/lit/ds/symlink/tpd4e05u06-q1.pdf?HQS=dis-mous-null-mousermode-dsf-pf-null-wwe&ts=1663591265741&ref_url=https%253A%252F%252Fwww.mouser.com%252F"
			(at 0 0 180)
			(layer "F.Fab")
			(hide yes)
			(effects
				(font
					(size 1.27 1.27)
					(thickness 0.15)
				)
			)
		)
		(property "Manufacturer" "Texas Instruments"
			(at 0 0 180)
			(unlocked yes)
			(layer "B.Fab")
			(hide yes)
			(effects
				(font
					(size 1 1)
					(thickness 0.15)
				)
				(justify mirror)
			)
		)
		(property "MPN" "TPD4E05U06QDQARQ1"
			(at 0 0 180)
			(unlocked yes)
			(layer "B.Fab")
			(hide yes)
			(effects
				(font
					(size 1 1)
					(thickness 0.15)
				)
				(justify mirror)
			)
		)
		(property "Author" "Antmicro"
			(at 0 0 180)
			(unlocked yes)
			(layer "B.Fab")
			(hide yes)
			(effects
				(font
					(size 1 1)
					(thickness 0.15)
				)
				(justify mirror)
			)
		)
		(property "License" "Apache-2.0"
			(at 0 0 180)
			(unlocked yes)
			(layer "B.Fab")
			(hide yes)
			(effects
				(font
					(size 1 1)
					(thickness 0.15)
				)
				(justify mirror)
			)
		)
		(sheetname "/HDMI + SD Card/")
		(sheetfile "hdmi-sd-card.kicad_sch")
		(attr smd)
		(fp_line
			(start 0.498 1.401)
			(end -0.5 1.401)
			(stroke
				(width 0.15)
				(type solid)
			)
			(layer "B.SilkS")
		)
		(fp_line
			(start 0.498 -1.398)
			(end -0.5 -1.398)
			(stroke
				(width 0.15)
				(type solid)
			)
			(layer "B.SilkS")
		)
		(fp_circle
			(center -0.68 1.27)
			(end -0.63 1.27)
			(stroke
				(width 0.15)
				(type solid)
			)
			(fill yes)
			(layer "B.SilkS")
		)
		(fp_rect
			(start -0.8 1.5)
			(end 0.8 -1.499)
			(stroke
				(width 0.05)
				(type solid)
			)
			(fill no)
			(layer "B.CrtYd")
		)
		(fp_line
			(start 0.498 1.25)
			(end 0.498 -1.249)
			(stroke
				(width 0.15)
				(type solid)
			)
			(layer "B.Fab")
		)
		(fp_line
			(start 0.498 1.25)
			(end -0.25 1.25)
			(stroke
				(width 0.15)
				(type solid)
			)
			(layer "B.Fab")
		)
		(fp_line
			(start -0.25 1.25)
			(end -0.5 1)
			(stroke
				(width 0.15)
				(type solid)
			)
			(layer "B.Fab")
		)
		(fp_line
			(start -0.5 1)
			(end -0.5 -1.249)
			(stroke
				(width 0.15)
				(type solid)
			)
			(layer "B.Fab")
		)
		(fp_line
			(start -0.5 -1.249)
			(end 0.498 -1.249)
			(stroke
				(width 0.15)
				(type solid)
			)
			(layer "B.Fab")
		)
		(fp_text user "${REFERENCE}"
			(at -0.802 -4.498 0)
			(layer "B.Fab")
			(effects
				(font
					(size 0.7 0.7)
					(thickness 0.15)
				)
				(justify left bottom mirror)
			)
		)
		(fp_text user "Author: Antmicro"
			(at -0.802 -5.7 0)
			(layer "B.Fab")
			(effects
				(font
					(size 0.7 0.7)
					(thickness 0.15)
				)
				(justify left bottom mirror)
			)
		)
		(fp_text user "License: Apache-2.0"
			(at -0.802 -6.9 0)
			(layer "B.Fab")
			(effects
				(font
					(size 0.7 0.7)
					(thickness 0.15)
				)
				(justify left bottom mirror)
			)
		)
		(pad "1" smd roundrect
			(at -0.387 1 270)
			(size 0.25 0.55)
			(layers "B.Cu" "B.Mask" "B.Paste")
			(roundrect_rratio 0.25)
			(net 480 "/HDMI + SD Card/HDMI_IN_5V.SDA")
			(pintype "passive")
		)
		(pad "2" smd roundrect
			(at -0.387 0.5 270)
			(size 0.25 0.55)
			(layers "B.Cu" "B.Mask" "B.Paste")
			(roundrect_rratio 0.25)
			(net 499 "/HDMI + SD Card/HDMI_IN_5V.SCL")
			(pintype "passive")
		)
		(pad "3" smd roundrect
			(at -0.387 0 270)
			(size 0.4 0.55)
			(layers "B.Cu" "B.Mask" "B.Paste")
			(roundrect_rratio 0.25)
			(net 1 "GND")
			(pintype "power_in")
		)
		(pad "4" smd roundrect
			(at -0.387 -0.498 270)
			(size 0.25 0.55)
			(layers "B.Cu" "B.Mask" "B.Paste")
			(roundrect_rratio 0.25)
			(net 297 "/HDMI + SD Card/HDMI_IN_5V")
			(pintype "passive")
		)
		(pad "5" smd roundrect
			(at -0.387 -0.998 270)
			(size 0.25 0.55)
			(layers "B.Cu" "B.Mask" "B.Paste")
			(roundrect_rratio 0.25)
			(net 604 "/HDMI + SD Card/HDMI_IN_HPD_CONN")
			(pintype "passive")
		)
		(pad "6" smd roundrect
			(at 0.385 -0.998 270)
			(size 0.25 0.55)
			(layers "B.Cu" "B.Mask" "B.Paste")
			(roundrect_rratio 0.25)
			(net 604 "/HDMI + SD Card/HDMI_IN_HPD_CONN")
			(pintype "passive")
		)
		(pad "7" smd roundrect
			(at 0.385 -0.498 270)
			(size 0.25 0.55)
			(layers "B.Cu" "B.Mask" "B.Paste")
			(roundrect_rratio 0.25)
			(net 297 "/HDMI + SD Card/HDMI_IN_5V")
			(pintype "passive")
		)
		(pad "8" smd roundrect
			(at 0.385 0 270)
			(size 0.4 0.55)
			(layers "B.Cu" "B.Mask" "B.Paste")
			(roundrect_rratio 0.25)
			(net 1 "GND")
			(pintype "passive")
		)
		(pad "9" smd roundrect
			(at 0.385 0.5 270)
			(size 0.25 0.55)
			(layers "B.Cu" "B.Mask" "B.Paste")
			(roundrect_rratio 0.25)
			(net 499 "/HDMI + SD Card/HDMI_IN_5V.SCL")
			(pintype "passive")
		)
		(pad "10" smd roundrect
			(at 0.385 1 270)
			(size 0.25 0.55)
			(layers "B.Cu" "B.Mask" "B.Paste")
			(roundrect_rratio 0.25)
			(net 480 "/HDMI + SD Card/HDMI_IN_5V.SDA")
			(pintype "passive")
		)
	)
	(footprint "antmicro-footprints:R_0402_1005Metric_EIA"
		(layer "B.Cu")
		(at 195.5 157 180)
		(descr "Resistor SMD 0402 (1005 Metric), square (rectangular) end terminal, IPC_7351 nominal, (Body size source: IPC-SM-782 page 76, https://www.pcb-3d.com/wordpress/wp-content/uploads/ipc-sm-782a_amendment_1_and_2.pdf)")
		(tags "resistor 0402")
		(property "Reference" "R21"
			(at 30.05 10.4 0)
			(layer "B.SilkS")
			(effects
				(font
					(size 0.7 0.7)
					(thickness 0.15)
				)
				(justify left bottom mirror)
			)
		)
		(property "Value" "R_100R_0402"
			(at 0 -1.169 0)
			(layer "B.Fab")
			(effects
				(font
					(size 0.7 0.7)
					(thickness 0.15)
				)
				(justify left bottom mirror)
			)
		)
		(property "Datasheet" "https://www.bourns.com/docs/product-datasheets/cr.pdf"
			(at 0 0 180)
			(layer "F.Fab")
			(hide yes)
			(effects
				(font
					(size 1.27 1.27)
					(thickness 0.15)
				)
			)
		)
		(property "Manufacturer" "Bourns"
			(at 0 0 180)
			(unlocked yes)
			(layer "B.Fab")
			(hide yes)
			(effects
				(font
					(size 1 1)
					(thickness 0.15)
				)
				(justify mirror)
			)
		)
		(property "MPN" "CR0402-FX-1000GLF"
			(at 0 0 180)
			(unlocked yes)
			(layer "B.Fab")
			(hide yes)
			(effects
				(font
					(size 1 1)
					(thickness 0.15)
				)
				(justify mirror)
			)
		)
		(property "Val" "100R"
			(at 0 0 180)
			(unlocked yes)
			(layer "B.Fab")
			(hide yes)
			(effects
				(font
					(size 1 1)
					(thickness 0.15)
				)
				(justify mirror)
			)
		)
		(property "License" "Apache-2.0"
			(at 0 0 180)
			(unlocked yes)
			(layer "B.Fab")
			(hide yes)
			(effects
				(font
					(size 1 1)
					(thickness 0.15)
				)
				(justify mirror)
			)
		)
		(property "Author" "Antmicro"
			(at 0 0 180)
			(unlocked yes)
			(layer "B.Fab")
			(hide yes)
			(effects
				(font
					(size 1 1)
					(thickness 0.15)
				)
				(justify mirror)
			)
		)
		(property "Tolerance" "1%"
			(at 0 0 180)
			(unlocked yes)
			(layer "B.Fab")
			(hide yes)
			(effects
				(font
					(size 1 1)
					(thickness 0.15)
				)
				(justify mirror)
			)
		)
		(sheetname "/FPGA Config/")
		(sheetfile "fpga-config.kicad_sch")
		(attr smd)
		(fp_rect
			(start -0.95 0.45)
			(end 0.95 -0.45)
			(stroke
				(width 0.05)
				(type default)
			)
			(fill no)
			(layer "B.CrtYd")
		)
		(fp_line
			(start 0.499 0.25)
			(end 0.499 -0.249)
			(stroke
				(width 0.15)
				(type solid)
			)
			(layer "B.Fab")
		)
		(fp_line
			(start 0.499 -0.249)
			(end -0.5 -0.249)
			(stroke
				(width 0.15)
				(type solid)
			)
			(layer "B.Fab")
		)
		(fp_line
			(start -0.5 0.25)
			(end 0.499 0.25)
			(stroke
				(width 0.15)
				(type solid)
			)
			(layer "B.Fab")
		)
		(fp_line
			(start -0.5 -0.249)
			(end -0.5 0.25)
			(stroke
				(width 0.15)
				(type solid)
			)
			(layer "B.Fab")
		)
		(fp_text user "${REFERENCE}"
			(at -0.95 -3.169 0)
			(layer "B.Fab")
			(effects
				(font
					(size 0.7 0.7)
					(thickness 0.15)
				)
				(justify left bottom mirror)
			)
		)
		(fp_text user "License: Apache-2.0"
			(at -0.95 -4.369 0)
			(layer "B.Fab")
			(effects
				(font
					(size 0.7 0.7)
					(thickness 0.15)
				)
				(justify left bottom mirror)
			)
		)
		(fp_text user "Author: Antmicro"
			(at -0.95 -5.569 0)
			(layer "B.Fab")
			(effects
				(font
					(size 0.7 0.7)
					(thickness 0.15)
				)
				(justify left bottom mirror)
			)
		)
		(pad "1" smd roundrect
			(at -0.5 0 90)
			(size 0.6 0.6)
			(layers "B.Cu" "B.Mask" "B.Paste")
			(roundrect_rratio 0.25)
			(net 797 "+1V8")
			(pintype "passive")
		)
		(pad "2" smd roundrect
			(at 0.499 0 180)
			(size 0.6 0.6)
			(layers "B.Cu" "B.Mask" "B.Paste")
			(roundrect_rratio 0.25)
			(net 40 "/FPGA Config/PUDC_B")
			(pintype "passive")
		)
	)
	(footprint "antmicro-footprints:C_0402_1005Metric"
		(layer "B.Cu")
		(at 252.5 104.325 90)
		(descr "Capacitor SMD 0402")
		(tags "capacitor SMD 0402")
		(property "Reference" "C317"
			(at -1.25 -0.425 90)
			(layer "B.SilkS")
			(effects
				(font
					(size 0.7 0.7)
					(thickness 0.15)
				)
				(justify left top mirror)
			)
		)
		(property "Value" "C_100n_0402"
			(at -1.022927 -2.155213 90)
			(layer "B.Fab")
			(effects
				(font
					(size 0.7 0.7)
					(thickness 0.15)
				)
				(justify right bottom mirror)
			)
		)
		(property "Datasheet" "https://www.murata.com/products/productdetail?partno=GRM155R61H104KE14%23"
			(at 0 0 90)
			(layer "B.Fab")
			(hide yes)
			(effects
				(font
					(size 1.27 1.27)
					(thickness 0.15)
				)
				(justify mirror)
			)
		)
		(property "MPN" "GRM155R61H104KE14D"
			(at 0 0 90)
			(unlocked yes)
			(layer "B.Fab")
			(hide yes)
			(effects
				(font
					(size 1 1)
					(thickness 0.15)
				)
				(justify mirror)
			)
		)
		(property "Manufacturer" "Murata"
			(at 0 0 90)
			(unlocked yes)
			(layer "B.Fab")
			(hide yes)
			(effects
				(font
					(size 1 1)
					(thickness 0.15)
				)
				(justify mirror)
			)
		)
		(property "License" "Apache-2.0"
			(at 0 0 90)
			(unlocked yes)
			(layer "B.Fab")
			(hide yes)
			(effects
				(font
					(size 1 1)
					(thickness 0.15)
				)
				(justify mirror)
			)
		)
		(property "Author" "Antmicro"
			(at 0 0 90)
			(unlocked yes)
			(layer "B.Fab")
			(hide yes)
			(effects
				(font
					(size 1 1)
					(thickness 0.15)
				)
				(justify mirror)
			)
		)
		(property "Val" "100n"
			(at 0 0 90)
			(unlocked yes)
			(layer "B.Fab")
			(hide yes)
			(effects
				(font
					(size 1 1)
					(thickness 0.15)
				)
				(justify mirror)
			)
		)
		(property "Voltage" "50V"
			(at 0 0 90)
			(unlocked yes)
			(layer "B.Fab")
			(hide yes)
			(effects
				(font
					(size 1 1)
					(thickness 0.15)
				)
				(justify mirror)
			)
		)
		(property "Dielectric" "X5R"
			(at 0 0 90)
			(unlocked yes)
			(layer "B.Fab")
			(hide yes)
			(effects
				(font
					(size 1 1)
					(thickness 0.15)
				)
				(justify mirror)
			)
		)
		(sheetname "/DDR5 RDIMM/")
		(sheetfile "ddr5-rdimm.kicad_sch")
		(attr smd)
		(fp_rect
			(start -0.925 0.47)
			(end 0.925 -0.47)
			(stroke
				(width 0.05)
				(type default)
			)
			(fill no)
			(layer "B.CrtYd")
		)
		(fp_line
			(start 0.504 -0.248)
			(end -0.494 -0.248)
			(stroke
				(width 0.15)
				(type solid)
			)
			(layer "B.Fab")
		)
		(fp_line
			(start -0.494 -0.248)
			(end -0.494 0.25)
			(stroke
				(width 0.15)
				(type solid)
			)
			(layer "B.Fab")
		)
		(fp_line
			(start 0.504 0.25)
			(end 0.504 -0.248)
			(stroke
				(width 0.15)
				(type solid)
			)
			(layer "B.Fab")
		)
		(fp_line
			(start -0.494 0.25)
			(end 0.504 0.25)
			(stroke
				(width 0.15)
				(type solid)
			)
			(layer "B.Fab")
		)
		(fp_text user "License: Apache-2.0"
			(at -0.939 -5.799 270)
			(layer "B.Fab")
			(effects
				(font
					(size 0.7 0.7)
					(thickness 0.15)
				)
				(justify left bottom mirror)
			)
		)
		(fp_text user "${REFERENCE}"
			(at -0.939 -4.599 270)
			(layer "B.Fab")
			(effects
				(font
					(size 0.7 0.7)
					(thickness 0.15)
				)
				(justify left bottom mirror)
			)
		)
		(fp_text user "Author: Antmicro"
			(at -0.939 -3.399 270)
			(layer "B.Fab")
			(effects
				(font
					(size 0.7 0.7)
					(thickness 0.15)
				)
				(justify left bottom mirror)
			)
		)
		(pad "1" smd roundrect
			(at -0.48 0 90)
			(size 0.59 0.64)
			(layers "B.Cu" "B.Mask" "B.Paste")
			(roundrect_rratio 0.25)
			(net 1 "GND")
			(pintype "passive")
		)
		(pad "2" smd roundrect
			(at 0.48 0 90)
			(size 0.59 0.64)
			(layers "B.Cu" "B.Mask" "B.Paste")
			(roundrect_rratio 0.25)
			(net 803 "/DDR5 RDIMM/VIN_MGMT")
			(pintype "passive")
		)
	)
	(footprint "antmicro-footprints:R_0402_1005Metric_EIA"
		(layer "B.Cu")
		(at 194 156.499 90)
		(descr "Resistor SMD 0402 (1005 Metric), square (rectangular) end terminal, IPC_7351 nominal, (Body size source: IPC-SM-782 page 76, https://www.pcb-3d.com/wordpress/wp-content/uploads/ipc-sm-782a_amendment_1_and_2.pdf)")
		(tags "resistor 0402")
		(property "Reference" "R22"
			(at 9.724 -30.65 90)
			(layer "B.SilkS")
			(effects
				(font
					(size 0.7 0.7)
					(thickness 0.15)
				)
				(justify right bottom mirror)
			)
		)
		(property "Value" "R_100R_0402"
			(at 0 -1.169 90)
			(layer "B.Fab")
			(effects
				(font
					(size 0.7 0.7)
					(thickness 0.15)
				)
				(justify right bottom mirror)
			)
		)
		(property "Datasheet" "https://www.bourns.com/docs/product-datasheets/cr.pdf"
			(at 0 0 90)
			(layer "F.Fab")
			(hide yes)
			(effects
				(font
					(size 1.27 1.27)
					(thickness 0.15)
				)
			)
		)
		(property "Manufacturer" "Bourns"
			(at 0 0 90)
			(unlocked yes)
			(layer "B.Fab")
			(hide yes)
			(effects
				(font
					(size 1 1)
					(thickness 0.15)
				)
				(justify mirror)
			)
		)
		(property "MPN" "CR0402-FX-1000GLF"
			(at 0 0 90)
			(unlocked yes)
			(layer "B.Fab")
			(hide yes)
			(effects
				(font
					(size 1 1)
					(thickness 0.15)
				)
				(justify mirror)
			)
		)
		(property "Val" "100R"
			(at 0 0 90)
			(unlocked yes)
			(layer "B.Fab")
			(hide yes)
			(effects
				(font
					(size 1 1)
					(thickness 0.15)
				)
				(justify mirror)
			)
		)
		(property "License" "Apache-2.0"
			(at 0 0 90)
			(unlocked yes)
			(layer "B.Fab")
			(hide yes)
			(effects
				(font
					(size 1 1)
					(thickness 0.15)
				)
				(justify mirror)
			)
		)
		(property "Author" "Antmicro"
			(at 0 0 90)
			(unlocked yes)
			(layer "B.Fab")
			(hide yes)
			(effects
				(font
					(size 1 1)
					(thickness 0.15)
				)
				(justify mirror)
			)
		)
		(property "Tolerance" "1%"
			(at 0 0 90)
			(unlocked yes)
			(layer "B.Fab")
			(hide yes)
			(effects
				(font
					(size 1 1)
					(thickness 0.15)
				)
				(justify mirror)
			)
		)
		(sheetname "/FPGA Config/")
		(sheetfile "fpga-config.kicad_sch")
		(attr smd exclude_from_bom dnp)
		(fp_rect
			(start -0.95 0.45)
			(end 0.95 -0.45)
			(stroke
				(width 0.05)
				(type default)
			)
			(fill no)
			(layer "B.CrtYd")
		)
		(fp_line
			(start 0.499 -0.249)
			(end -0.5 -0.249)
			(stroke
				(width 0.15)
				(type solid)
			)
			(layer "B.Fab")
		)
		(fp_line
			(start -0.5 -0.249)
			(end -0.5 0.25)
			(stroke
				(width 0.15)
				(type solid)
			)
			(layer "B.Fab")
		)
		(fp_line
			(start 0.499 0.25)
			(end 0.499 -0.249)
			(stroke
				(width 0.15)
				(type solid)
			)
			(layer "B.Fab")
		)
		(fp_line
			(start -0.5 0.25)
			(end 0.499 0.25)
			(stroke
				(width 0.15)
				(type solid)
			)
			(layer "B.Fab")
		)
		(fp_text user "Author: Antmicro"
			(at -0.95 -5.569 270)
			(layer "B.Fab")
			(effects
				(font
					(size 0.7 0.7)
					(thickness 0.15)
				)
				(justify left bottom mirror)
			)
		)
		(fp_text user "License: Apache-2.0"
			(at -0.95 -4.369 270)
			(layer "B.Fab")
			(effects
				(font
					(size 0.7 0.7)
					(thickness 0.15)
				)
				(justify left bottom mirror)
			)
		)
		(fp_text user "${REFERENCE}"
			(at -0.95 -3.169 270)
			(layer "B.Fab")
			(effects
				(font
					(size 0.7 0.7)
					(thickness 0.15)
				)
				(justify left bottom mirror)
			)
		)
		(pad "1" smd roundrect
			(at -0.5 0)
			(size 0.6 0.6)
			(layers "B.Cu" "B.Mask" "B.Paste")
			(roundrect_rratio 0.25)
			(net 40 "/FPGA Config/PUDC_B")
			(pintype "passive")
		)
		(pad "2" smd roundrect
			(at 0.499 0 90)
			(size 0.6 0.6)
			(layers "B.Cu" "B.Mask" "B.Paste")
			(roundrect_rratio 0.25)
			(net 1 "GND")
			(pintype "passive")
		)
	)
)
